# T6G (Grand Teton) — schematic netlist excerpt (pin names and nets, part order shuffled) for the footprints in the layout excerpt that follows; sources: Cadence DE-HDL packaged netlist, KiCad conversion of 04192023_DAF0TMB3IC0_F0TG_MB_C_brd_V02_OCP.brd

R162  Q_RES  0 5% CHIP  pkg 0402LF  page 160 : A = SMB_CPU0_CPU1_APML_SDA ; B = SMB_CPU0_CPU1_APML_BUF2_SDA
R1678  Q_RES  10 1% CHIP  pkg 0402LF  page 90 : A = I3C_SPD_DDRAF_CPU0_SDA ; B = I3C_SPD_DDRE_CPU0_SDA
R6748  Q_RES  0 5% CHIP  pkg 0201LF  page 184 : A = SMB_RT_CPU1_P2_R_SDA ; B = SMB_RT_CPU1_P2_SDA

(kicad_pcb
	(version 20260206)
	(generator "pcbnew")
	(generator_version "10.0")
	(general
		(thickness 1.6)
		(legacy_teardrops no)
	)
	(paper "A4")
	(title_block
		(title "04192023_DAF0TMB3IC0_F0TG_MB_C_brd_V02_OCP.brd")
		(comment 1 "Grand Teton / footprints 7472-7474 of 8354")
	)
	(layers
		(0 "F.Cu" signal "TOP")
		(4 "In1.Cu" signal "GND")
		(6 "In2.Cu" signal "IN1")
		(8 "In3.Cu" signal "GND1")
		(10 "In4.Cu" signal "IN2")
		(12 "In5.Cu" signal "GND2")
		(14 "In6.Cu" signal "IN3")
		(16 "In7.Cu" signal "GND3")
		(18 "In8.Cu" signal "VCC")
		(20 "In9.Cu" signal "VCC1")
		(22 "In10.Cu" signal "GND4")
		(24 "In11.Cu" signal "IN4")
		(26 "In12.Cu" signal "GND5")
		(28 "In13.Cu" signal "IN5")
		(30 "In14.Cu" signal "GND6")
		(32 "In15.Cu" signal "IN6")
		(34 "In16.Cu" signal "GND7")
		(2 "B.Cu" signal "BOTTOM")
		(9 "F.Adhes" user "F.Adhesive")
		(11 "B.Adhes" user "B.Adhesive")
		(13 "F.Paste" user "Package Geometry/Pastemask Top")
		(15 "B.Paste" user "Package Geometry/Pastemask Bottom")
		(5 "F.SilkS" user "Ref Des/Silkscreen Top")
		(7 "B.SilkS" user "Ref Des/Silkscreen Bottom")
		(1 "F.Mask" user "Board Geometry/Soldermask Top")
		(3 "B.Mask" user "Board Geometry/Soldermask Bottom")
		(17 "Dwgs.User" user "User.Drawings")
		(19 "Cmts.User" user "User.Comments")
		(21 "Eco1.User" user "User.Eco1")
		(23 "Eco2.User" user "User.Eco2")
		(25 "Edge.Cuts" user "Board Geometry/Outline")
		(27 "Margin" user)
		(31 "F.CrtYd" user "Package Geometry/Place Bound Top")
		(29 "B.CrtYd" user "Package Geometry/Place Bound Bottom")
		(35 "F.Fab" user "Ref Des/Assembly Top")
		(33 "B.Fab" user "Ref Des/Assembly Bottom")
	)
	(footprint ""
		(layer "B.Cu")
		(at 233.68 -228.092)
		(property "Reference" "R162"
			(at 0 0 0)
			(layer "B.SilkS")
			(hide yes)
			(effects
				(font
					(size 1.27 1.27)
				)
				(justify mirror)
			)
		)
		(property "Value" ""
			(at 0 0 0)
			(layer "B.Fab")
			(effects
				(font
					(size 1.27 1.27)
				)
				(justify mirror)
			)
		)
		(duplicate_pad_numbers_are_jumpers no)
		(fp_line
			(start -0.7874 -0.4064)
			(end -0.7874 0.4064)
			(stroke
				(width 0.1524)
				(type default)
			)
			(layer "B.SilkS")
		)
		(fp_line
			(start -0.7874 0.4064)
			(end 0.7874 0.4064)
			(stroke
				(width 0.1524)
				(type default)
			)
			(layer "B.SilkS")
		)
		(fp_line
			(start 0.7874 -0.4064)
			(end -0.7874 -0.4064)
			(stroke
				(width 0.1524)
				(type default)
			)
			(layer "B.SilkS")
		)
		(fp_line
			(start 0.7874 0.4064)
			(end 0.7874 -0.4064)
			(stroke
				(width 0.1524)
				(type default)
			)
			(layer "B.SilkS")
		)
		(fp_line
			(start -0.67945 -0.3048)
			(end -0.67945 0.3048)
			(stroke
				(width 0.1)
				(type default)
			)
			(layer "B.Fab")
		)
		(fp_line
			(start -0.67945 0.3048)
			(end -0.120396 0.3048)
			(stroke
				(width 0.1)
				(type default)
			)
			(layer "B.Fab")
		)
		(fp_line
			(start -0.12065 -0.3048)
			(end -0.67945 -0.3048)
			(stroke
				(width 0.1)
				(type default)
			)
			(layer "B.Fab")
		)
		(fp_line
			(start -0.12065 -0.2794)
			(end -0.12065 -0.3048)
			(stroke
				(width 0.1)
				(type default)
			)
			(layer "B.Fab")
		)
		(fp_line
			(start -0.120396 0.2794)
			(end 0.12065 0.2794)
			(stroke
				(width 0.1)
				(type default)
			)
			(layer "B.Fab")
		)
		(fp_line
			(start -0.120396 0.3048)
			(end -0.120396 0.2794)
			(stroke
				(width 0.1)
				(type default)
			)
			(layer "B.Fab")
		)
		(fp_line
			(start 0.12065 -0.305054)
			(end 0.12065 -0.2794)
			(stroke
				(width 0.1)
				(type default)
			)
			(layer "B.Fab")
		)
		(fp_line
			(start 0.12065 -0.2794)
			(end -0.12065 -0.2794)
			(stroke
				(width 0.1)
				(type default)
			)
			(layer "B.Fab")
		)
		(fp_line
			(start 0.12065 0.2794)
			(end 0.12065 0.3048)
			(stroke
				(width 0.1)
				(type default)
			)
			(layer "B.Fab")
		)
		(fp_line
			(start 0.12065 0.3048)
			(end 0.67945 0.3048)
			(stroke
				(width 0.1)
				(type default)
			)
			(layer "B.Fab")
		)
		(fp_line
			(start 0.67945 -0.305054)
			(end 0.12065 -0.305054)
			(stroke
				(width 0.1)
				(type default)
			)
			(layer "B.Fab")
		)
		(fp_line
			(start 0.67945 0.3048)
			(end 0.67945 -0.305054)
			(stroke
				(width 0.1)
				(type default)
			)
			(layer "B.Fab")
		)
		(pad "1" smd rect
			(at 0.40005 0)
			(size 0.4572 0.508)
			(layers "B.Cu" "B.Mask" "B.Paste")
			(net "SMB_CPU0_CPU1_APML_SDA")
		)
		(pad "2" smd rect
			(at -0.40005 0)
			(size 0.4572 0.508)
			(layers "B.Cu" "B.Mask" "B.Paste")
			(net "SMB_CPU0_CPU1_APML_BUF2_SDA")
		)
	)
	(footprint ""
		(layer "B.Cu")
		(at 276.436582 -195.859146 180)
		(property "Reference" "R1678"
			(at 0 0 0)
			(layer "B.SilkS")
			(hide yes)
			(effects
				(font
					(size 1.27 1.27)
				)
				(justify mirror)
			)
		)
		(property "Value" ""
			(at 0 0 0)
			(layer "B.Fab")
			(effects
				(font
					(size 1.27 1.27)
				)
				(justify mirror)
			)
		)
		(duplicate_pad_numbers_are_jumpers no)
		(fp_line
			(start 0.7874 0.4064)
			(end 0.7874 -0.4064)
			(stroke
				(width 0.1524)
				(type default)
			)
			(layer "B.SilkS")
		)
		(fp_line
			(start 0.7874 -0.4064)
			(end -0.7874 -0.4064)
			(stroke
				(width 0.1524)
				(type default)
			)
			(layer "B.SilkS")
		)
		(fp_line
			(start -0.7874 0.4064)
			(end 0.7874 0.4064)
			(stroke
				(width 0.1524)
				(type default)
			)
			(layer "B.SilkS")
		)
		(fp_line
			(start -0.7874 -0.4064)
			(end -0.7874 0.4064)
			(stroke
				(width 0.1524)
				(type default)
			)
			(layer "B.SilkS")
		)
		(fp_line
			(start 0.67945 0.3048)
			(end 0.67945 -0.305054)
			(stroke
				(width 0.1)
				(type default)
			)
			(layer "B.Fab")
		)
		(fp_line
			(start 0.67945 -0.305054)
			(end 0.12065 -0.305054)
			(stroke
				(width 0.1)
				(type default)
			)
			(layer "B.Fab")
		)
		(fp_line
			(start 0.12065 0.3048)
			(end 0.67945 0.3048)
			(stroke
				(width 0.1)
				(type default)
			)
			(layer "B.Fab")
		)
		(fp_line
			(start 0.12065 0.2794)
			(end 0.12065 0.3048)
			(stroke
				(width 0.1)
				(type default)
			)
			(layer "B.Fab")
		)
		(fp_line
			(start 0.12065 -0.2794)
			(end -0.12065 -0.2794)
			(stroke
				(width 0.1)
				(type default)
			)
			(layer "B.Fab")
		)
		(fp_line
			(start 0.12065 -0.305054)
			(end 0.12065 -0.2794)
			(stroke
				(width 0.1)
				(type default)
			)
			(layer "B.Fab")
		)
		(fp_line
			(start -0.120396 0.3048)
			(end -0.120396 0.2794)
			(stroke
				(width 0.1)
				(type default)
			)
			(layer "B.Fab")
		)
		(fp_line
			(start -0.120396 0.2794)
			(end 0.12065 0.2794)
			(stroke
				(width 0.1)
				(type default)
			)
			(layer "B.Fab")
		)
		(fp_line
			(start -0.12065 -0.2794)
			(end -0.12065 -0.3048)
			(stroke
				(width 0.1)
				(type default)
			)
			(layer "B.Fab")
		)
		(fp_line
			(start -0.12065 -0.3048)
			(end -0.67945 -0.3048)
			(stroke
				(width 0.1)
				(type default)
			)
			(layer "B.Fab")
		)
		(fp_line
			(start -0.67945 0.3048)
			(end -0.120396 0.3048)
			(stroke
				(width 0.1)
				(type default)
			)
			(layer "B.Fab")
		)
		(fp_line
			(start -0.67945 -0.3048)
			(end -0.67945 0.3048)
			(stroke
				(width 0.1)
				(type default)
			)
			(layer "B.Fab")
		)
		(pad "1" smd circle
			(at 0.40005 0)
			(size 0 0)
			(layers "B.Cu" "B.Mask" "B.Paste")
			(net "I3C_SPD_DDRAF_CPU0_SDA")
		)
		(pad "2" smd circle
			(at -0.40005 0)
			(size 0 0)
			(layers "B.Cu" "B.Mask" "B.Paste")
			(net "I3C_SPD_DDRE_CPU0_SDA")
		)
	)
	(footprint ""
		(layer "B.Cu")
		(at 218.059 -340.868 180)
		(property "Reference" "R6748"
			(at 0 0 0)
			(layer "B.SilkS")
			(hide yes)
			(effects
				(font
					(size 1.27 1.27)
				)
				(justify mirror)
			)
		)
		(property "Value" ""
			(at 0 0 0)
			(layer "B.Fab")
			(effects
				(font
					(size 1.27 1.27)
				)
				(justify mirror)
			)
		)
		(duplicate_pad_numbers_are_jumpers no)
		(fp_line
			(start 0.32512 0.175006)
			(end 0.32512 -0.175006)
			(stroke
				(width 0.1)
				(type default)
			)
			(layer "B.Fab")
		)
		(fp_line
			(start 0.32512 -0.175006)
			(end -0.32512 -0.175006)
			(stroke
				(width 0.1)
				(type default)
			)
			(layer "B.Fab")
		)
		(fp_line
			(start -0.32512 0.175006)
			(end 0.32512 0.175006)
			(stroke
				(width 0.1)
				(type default)
			)
			(layer "B.Fab")
		)
		(fp_line
			(start -0.32512 -0.175006)
			(end -0.32512 0.175006)
			(stroke
				(width 0.1)
				(type default)
			)
			(layer "B.Fab")
		)
		(pad "1" smd rect
			(at 0.2667 0)
			(size 0.3048 0.381)
			(layers "B.Cu" "B.Mask" "B.Paste")
			(net "SMB_RT_CPU1_P2_R_SDA")
		)
		(pad "2" smd rect
			(at -0.2667 0 180)
			(size 0.3048 0.381)
			(layers "B.Cu" "B.Mask" "B.Paste")
			(net "SMB_RT_CPU1_P2_SDA")
		)
	)
)
